(kicad_pcb
	(version 20260206)
	(generator "pcbnew")
	(generator_version "10.0")
	(general
		(thickness 1.6)
		(legacy_teardrops no)
	)
	(paper "A4")
	(title_block
		(title "15969-1a.1015WZS0858.brd")
		(comment 1 "Tioga Pass / footprints 94-101 of 295")
	)
	(layers
		(0 "F.Cu" signal "TOP")
		(4 "In1.Cu" signal "L2GND")
		(6 "In2.Cu" signal "L3")
		(8 "In3.Cu" signal "L4")
		(10 "In4.Cu" signal "L5GND")
		(2 "B.Cu" signal "BOTTOM")
		(9 "F.Adhes" user "F.Adhesive")
		(11 "B.Adhes" user "B.Adhesive")
		(13 "F.Paste" user "Package Geometry/Pastemask Top")
		(15 "B.Paste" user "Package Geometry/Pastemask Bottom")
		(5 "F.SilkS" user "Ref Des/Silkscreen Top")
		(7 "B.SilkS" user "Ref Des/Silkscreen Bottom")
		(1 "F.Mask" user "Board Geometry/Soldermask Top")
		(3 "B.Mask" user "Board Geometry/Soldermask Bottom")
		(17 "Dwgs.User" user "User.Drawings")
		(19 "Cmts.User" user "User.Comments")
		(21 "Eco1.User" user "User.Eco1")
		(23 "Eco2.User" user "User.Eco2")
		(25 "Edge.Cuts" user "Board Geometry/Outline")
		(27 "Margin" user)
		(31 "F.CrtYd" user "Package Geometry/Place Bound Top")
		(29 "B.CrtYd" user "Package Geometry/Place Bound Bottom")
		(35 "F.Fab" user "Ref Des/Assembly Top")
		(33 "B.Fab" user "Ref Des/Assembly Bottom")
	)
	(footprint ""
		(layer "F.Cu")
		(at 131.2418 -29.5148 -90)
		(property "Reference" "CU11"
			(at 0 0 270)
			(layer "F.SilkS")
			(hide yes)
			(effects
				(font
					(size 1.27 1.27)
				)
			)
		)
		(property "Value" "SC18P50V2JN-1-GP"
			(at 1.1811 -2.7051 270)
			(unlocked yes)
			(layer "F.Fab")
			(hide yes)
			(effects
				(font
					(size 1.016 1.016)
					(thickness 0.1524)
				)
			)
		)
		(property "Device Type" "C402H22"
			(at 1.1811 -4.2291 270)
			(unlocked yes)
			(layer "F.Fab")
			(hide yes)
			(effects
				(font
					(size 1.016 1.016)
					(thickness 0.1524)
				)
			)
		)
		(duplicate_pad_numbers_are_jumpers no)
		(fp_rect
			(start -0.4318 0.9525)
			(end 0.4318 -0.9525)
			(stroke
				(width 0)
				(type default)
			)
			(fill no)
			(layer "F.CrtYd")
		)
		(fp_rect
			(start -0.4318 0.9525)
			(end 0.4318 -0.9525)
			(stroke
				(width 0)
				(type default)
			)
			(fill no)
			(layer "F.Fab")
		)
		(pad "1" smd custom
			(at 0 -0.4445 270)
			(size 0.1524 0.1524)
			(layers "F.Cu" "F.Mask" "F.Paste")
			(net "USB_HUB_XTAL_IN")
			(options
				(clearance outline)
				(anchor circle)
			)
			(primitives
				(gr_poly
					(pts
						(arc
							(start 0.3048 -0.2032)
							(mid 0.275042 -0.275042)
							(end 0.2032 -0.3048)
						)
						(arc
							(start -0.2032 -0.3048)
							(mid -0.275042 -0.275042)
							(end -0.3048 -0.2032)
						)
						(arc
							(start -0.3048 0.2032)
							(mid -0.275042 0.275042)
							(end -0.2032 0.3048)
						)
						(arc
							(start 0.2032 0.3048)
							(mid 0.275042 0.275042)
							(end 0.3048 0.2032)
						)
					)
					(width 0)
					(fill yes)
				)
			)
		)
		(pad "2" smd custom
			(at 0 0.4445 270)
			(size 0.1524 0.1524)
			(layers "F.Cu" "F.Mask" "F.Paste")
			(net "GND")
			(options
				(clearance outline)
				(anchor circle)
			)
			(primitives
				(gr_poly
					(pts
						(arc
							(start 0.3048 -0.2032)
							(mid 0.275042 -0.275042)
							(end 0.2032 -0.3048)
						)
						(arc
							(start -0.2032 -0.3048)
							(mid -0.275042 -0.275042)
							(end -0.3048 -0.2032)
						)
						(arc
							(start -0.3048 0.2032)
							(mid -0.275042 0.275042)
							(end -0.2032 0.3048)
						)
						(arc
							(start 0.2032 0.3048)
							(mid 0.275042 0.275042)
							(end 0.3048 0.2032)
						)
					)
					(width 0)
					(fill yes)
				)
			)
		)
	)
	(footprint ""
		(layer "F.Cu")
		(at 19.2278 -31.9532 180)
		(property "Reference" "C93"
			(at 0 0 180)
			(layer "F.SilkS")
			(hide yes)
			(effects
				(font
					(size 1.27 1.27)
				)
			)
		)
		(property "Value" "SC22U16V5MX-4-GP"
			(at -0.0762 -6.1214 180)
			(unlocked yes)
			(layer "F.Fab")
			(hide yes)
			(effects
				(font
					(size 1.016 1.016)
					(thickness 0.1524)
				)
			)
		)
		(property "Device Type" "C805H58"
			(at -0.0762 -8.1534 180)
			(unlocked yes)
			(layer "F.Fab")
			(hide yes)
			(effects
				(font
					(size 1.016 1.016)
					(thickness 0.1524)
				)
			)
		)
		(duplicate_pad_numbers_are_jumpers no)
		(fp_line
			(start 0.635 0)
			(end -0.635 0)
			(stroke
				(width 0.508)
				(type default)
			)
			(layer "F.SilkS")
		)
		(fp_rect
			(start -0.9652 1.778)
			(end 0.9652 -1.778)
			(stroke
				(width 0)
				(type default)
			)
			(fill no)
			(layer "F.CrtYd")
		)
		(fp_poly
			(pts
				(xy -0.9652 -1.778) (xy 0.9652 -1.778) (xy 0.9652 1.778) (xy -0.9652 1.778)
			)
			(stroke
				(width 0)
				(type default)
			)
			(fill no)
			(layer "F.Fab")
		)
		(pad "1" smd rect
			(at 0 -0.9652 180)
			(size 1.397 1.143)
			(layers "F.Cu" "F.Mask" "F.Paste")
			(net "P12V_SLOT3")
		)
		(pad "2" smd rect
			(at 0 0.9652 180)
			(size 1.397 1.143)
			(layers "F.Cu" "F.Mask" "F.Paste")
			(net "GND")
		)
	)
	(footprint ""
		(layer "F.Cu")
		(at 43.7261 -4.0259 90)
		(property "Reference" "C26"
			(at 0 0 90)
			(layer "F.SilkS")
			(hide yes)
			(effects
				(font
					(size 1.27 1.27)
				)
			)
		)
		(property "Value" "SCD1U16V2KX-3GP"
			(at 1.1811 -2.7051 90)
			(unlocked yes)
			(layer "F.Fab")
			(hide yes)
			(effects
				(font
					(size 1.016 1.016)
					(thickness 0.1524)
				)
			)
		)
		(property "Device Type" "C402H22"
			(at 1.1811 -4.2291 90)
			(unlocked yes)
			(layer "F.Fab")
			(hide yes)
			(effects
				(font
					(size 1.016 1.016)
					(thickness 0.1524)
				)
			)
		)
		(duplicate_pad_numbers_are_jumpers no)
		(fp_rect
			(start -0.4318 0.9525)
			(end 0.4318 -0.9525)
			(stroke
				(width 0)
				(type default)
			)
			(fill no)
			(layer "F.CrtYd")
		)
		(fp_rect
			(start -0.4318 0.9525)
			(end 0.4318 -0.9525)
			(stroke
				(width 0)
				(type default)
			)
			(fill no)
			(layer "F.Fab")
		)
		(pad "1" smd custom
			(at 0 -0.4445 90)
			(size 0.1524 0.1524)
			(layers "F.Cu" "F.Mask" "F.Paste")
			(net "P3V3_STBY")
			(options
				(clearance outline)
				(anchor circle)
			)
			(primitives
				(gr_poly
					(pts
						(arc
							(start 0.3048 -0.2032)
							(mid 0.275042 -0.275042)
							(end 0.2032 -0.3048)
						)
						(arc
							(start -0.2032 -0.3048)
							(mid -0.275042 -0.275042)
							(end -0.3048 -0.2032)
						)
						(arc
							(start -0.3048 0.2032)
							(mid -0.275042 0.275042)
							(end -0.2032 0.3048)
						)
						(arc
							(start 0.2032 0.3048)
							(mid 0.275042 0.275042)
							(end 0.3048 0.2032)
						)
					)
					(width 0)
					(fill yes)
				)
			)
		)
		(pad "2" smd custom
			(at 0 0.4445 90)
			(size 0.1524 0.1524)
			(layers "F.Cu" "F.Mask" "F.Paste")
			(net "GND")
			(options
				(clearance outline)
				(anchor circle)
			)
			(primitives
				(gr_poly
					(pts
						(arc
							(start 0.3048 -0.2032)
							(mid 0.275042 -0.275042)
							(end 0.2032 -0.3048)
						)
						(arc
							(start -0.2032 -0.3048)
							(mid -0.275042 -0.275042)
							(end -0.3048 -0.2032)
						)
						(arc
							(start -0.3048 0.2032)
							(mid -0.275042 0.275042)
							(end -0.2032 0.3048)
						)
						(arc
							(start 0.2032 0.3048)
							(mid 0.275042 0.275042)
							(end 0.3048 0.2032)
						)
					)
					(width 0)
					(fill yes)
				)
			)
		)
	)
	(footprint ""
		(layer "F.Cu")
		(at 26.2128 -18.6563 180)
		(property "Reference" "R63"
			(at 0 0 180)
			(layer "F.SilkS")
			(hide yes)
			(effects
				(font
					(size 1.27 1.27)
				)
			)
		)
		(property "Value" "0R2F-1-GP"
			(at 0.064008 -3.993896 180)
			(unlocked yes)
			(layer "F.Fab")
			(hide yes)
			(effects
				(font
					(size 1.016 1.016)
					(thickness 0.1524)
				)
			)
		)
		(property "Device Type" "R402H16"
			(at 0.064008 -5.517896 180)
			(unlocked yes)
			(layer "F.Fab")
			(hide yes)
			(effects
				(font
					(size 1.016 1.016)
					(thickness 0.1524)
				)
			)
		)
		(duplicate_pad_numbers_are_jumpers no)
		(fp_line
			(start 0.508 -0.9398)
			(end -0.508 -0.9398)
			(stroke
				(width 0.1524)
				(type default)
			)
			(layer "F.SilkS")
		)
		(fp_line
			(start -0.508 -0.9398)
			(end -0.508 0.9398)
			(stroke
				(width 0.1524)
				(type default)
			)
			(layer "F.SilkS")
		)
		(fp_rect
			(start -0.508 0.9398)
			(end 0.508 -0.9398)
			(stroke
				(width 0)
				(type default)
			)
			(fill no)
			(layer "F.CrtYd")
		)
		(fp_rect
			(start -0.508 0.9398)
			(end 0.508 -0.9398)
			(stroke
				(width 0)
				(type default)
			)
			(fill no)
			(layer "F.Fab")
		)
		(pad "1" smd custom
			(at 0 -0.4445 180)
			(size 0.1397 0.1397)
			(layers "F.Cu" "F.Mask" "F.Paste")
			(net "SMB_VMONITOR_SLOT2_MUX_SDA")
			(options
				(clearance outline)
				(anchor circle)
			)
			(primitives
				(gr_poly
					(pts
						(arc
							(start -0.1778 -0.2794)
							(mid -0.249642 -0.249642)
							(end -0.2794 -0.1778)
						)
						(arc
							(start -0.2794 0.1778)
							(mid -0.249642 0.249642)
							(end -0.1778 0.2794)
						)
						(arc
							(start 0.1778 0.2794)
							(mid 0.249642 0.249642)
							(end 0.2794 0.1778)
						)
						(arc
							(start 0.2794 -0.1778)
							(mid 0.249642 -0.249642)
							(end 0.1778 -0.2794)
						)
					)
					(width 0)
					(fill yes)
				)
			)
		)
		(pad "2" smd custom
			(at 0 0.4445 180)
			(size 0.1397 0.1397)
			(layers "F.Cu" "F.Mask" "F.Paste")
			(net "SMDAT_BMC_DEVICE")
			(options
				(clearance outline)
				(anchor circle)
			)
			(primitives
				(gr_poly
					(pts
						(arc
							(start -0.1778 -0.2794)
							(mid -0.249642 -0.249642)
							(end -0.2794 -0.1778)
						)
						(arc
							(start -0.2794 0.1778)
							(mid -0.249642 0.249642)
							(end -0.1778 0.2794)
						)
						(arc
							(start 0.1778 0.2794)
							(mid 0.249642 0.249642)
							(end 0.2794 0.1778)
						)
						(arc
							(start 0.2794 -0.1778)
							(mid 0.249642 -0.249642)
							(end 0.1778 -0.2794)
						)
					)
					(width 0)
					(fill yes)
				)
			)
		)
	)
	(footprint ""
		(layer "F.Cu")
		(at 104.648 -22.1996 -90)
		(property "Reference" "C33"
			(at 0 0 270)
			(layer "F.SilkS")
			(hide yes)
			(effects
				(font
					(size 1.27 1.27)
				)
			)
		)
		(property "Value" "SCD1U16V2KX-3GP"
			(at 1.1811 -2.7051 270)
			(unlocked yes)
			(layer "F.Fab")
			(hide yes)
			(effects
				(font
					(size 1.016 1.016)
					(thickness 0.1524)
				)
			)
		)
		(property "Device Type" "C402H22"
			(at 1.1811 -4.2291 270)
			(unlocked yes)
			(layer "F.Fab")
			(hide yes)
			(effects
				(font
					(size 1.016 1.016)
					(thickness 0.1524)
				)
			)
		)
		(duplicate_pad_numbers_are_jumpers no)
		(fp_rect
			(start -0.4318 0.9525)
			(end 0.4318 -0.9525)
			(stroke
				(width 0)
				(type default)
			)
			(fill no)
			(layer "F.CrtYd")
		)
		(fp_rect
			(start -0.4318 0.9525)
			(end 0.4318 -0.9525)
			(stroke
				(width 0)
				(type default)
			)
			(fill no)
			(layer "F.Fab")
		)
		(pad "1" smd custom
			(at 0 -0.4445 270)
			(size 0.1524 0.1524)
			(layers "F.Cu" "F.Mask" "F.Paste")
			(net "P3V3_STBY")
			(options
				(clearance outline)
				(anchor circle)
			)
			(primitives
				(gr_poly
					(pts
						(arc
							(start 0.3048 -0.2032)
							(mid 0.275042 -0.275042)
							(end 0.2032 -0.3048)
						)
						(arc
							(start -0.2032 -0.3048)
							(mid -0.275042 -0.275042)
							(end -0.3048 -0.2032)
						)
						(arc
							(start -0.3048 0.2032)
							(mid -0.275042 0.275042)
							(end -0.2032 0.3048)
						)
						(arc
							(start 0.2032 0.3048)
							(mid 0.275042 0.275042)
							(end 0.3048 0.2032)
						)
					)
					(width 0)
					(fill yes)
				)
			)
		)
		(pad "2" smd custom
			(at 0 0.4445 270)
			(size 0.1524 0.1524)
			(layers "F.Cu" "F.Mask" "F.Paste")
			(net "GND")
			(options
				(clearance outline)
				(anchor circle)
			)
			(primitives
				(gr_poly
					(pts
						(arc
							(start 0.3048 -0.2032)
							(mid 0.275042 -0.275042)
							(end 0.2032 -0.3048)
						)
						(arc
							(start -0.2032 -0.3048)
							(mid -0.275042 -0.275042)
							(end -0.3048 -0.2032)
						)
						(arc
							(start -0.3048 0.2032)
							(mid -0.275042 0.275042)
							(end -0.2032 0.3048)
						)
						(arc
							(start 0.2032 0.3048)
							(mid 0.275042 0.275042)
							(end 0.3048 0.2032)
						)
					)
					(width 0)
					(fill yes)
				)
			)
		)
	)
	(footprint ""
		(layer "F.Cu")
		(at 133.1722 -29.5148 90)
		(property "Reference" "CU12"
			(at 0 0 90)
			(layer "F.SilkS")
			(hide yes)
			(effects
				(font
					(size 1.27 1.27)
				)
			)
		)
		(property "Value" "SC18P50V2JN-1-GP"
			(at 1.1811 -2.7051 90)
			(unlocked yes)
			(layer "F.Fab")
			(hide yes)
			(effects
				(font
					(size 1.016 1.016)
					(thickness 0.1524)
				)
			)
		)
		(property "Device Type" "C402H22"
			(at 1.1811 -4.2291 90)
			(unlocked yes)
			(layer "F.Fab")
			(hide yes)
			(effects
				(font
					(size 1.016 1.016)
					(thickness 0.1524)
				)
			)
		)
		(duplicate_pad_numbers_are_jumpers no)
		(fp_rect
			(start -0.4318 0.9525)
			(end 0.4318 -0.9525)
			(stroke
				(width 0)
				(type default)
			)
			(fill no)
			(layer "F.CrtYd")
		)
		(fp_rect
			(start -0.4318 0.9525)
			(end 0.4318 -0.9525)
			(stroke
				(width 0)
				(type default)
			)
			(fill no)
			(layer "F.Fab")
		)
		(pad "1" smd custom
			(at 0 -0.4445 90)
			(size 0.1524 0.1524)
			(layers "F.Cu" "F.Mask" "F.Paste")
			(net "USB_HUB_XTAL_OUT")
			(options
				(clearance outline)
				(anchor circle)
			)
			(primitives
				(gr_poly
					(pts
						(arc
							(start 0.3048 -0.2032)
							(mid 0.275042 -0.275042)
							(end 0.2032 -0.3048)
						)
						(arc
							(start -0.2032 -0.3048)
							(mid -0.275042 -0.275042)
							(end -0.3048 -0.2032)
						)
						(arc
							(start -0.3048 0.2032)
							(mid -0.275042 0.275042)
							(end -0.2032 0.3048)
						)
						(arc
							(start 0.2032 0.3048)
							(mid 0.275042 0.275042)
							(end 0.3048 0.2032)
						)
					)
					(width 0)
					(fill yes)
				)
			)
		)
		(pad "2" smd custom
			(at 0 0.4445 90)
			(size 0.1524 0.1524)
			(layers "F.Cu" "F.Mask" "F.Paste")
			(net "GND")
			(options
				(clearance outline)
				(anchor circle)
			)
			(primitives
				(gr_poly
					(pts
						(arc
							(start 0.3048 -0.2032)
							(mid 0.275042 -0.275042)
							(end 0.2032 -0.3048)
						)
						(arc
							(start -0.2032 -0.3048)
							(mid -0.275042 -0.275042)
							(end -0.3048 -0.2032)
						)
						(arc
							(start -0.3048 0.2032)
							(mid -0.275042 0.275042)
							(end -0.2032 0.3048)
						)
						(arc
							(start 0.2032 0.3048)
							(mid 0.275042 0.275042)
							(end 0.3048 0.2032)
						)
					)
					(width 0)
					(fill yes)
				)
			)
		)
	)
	(footprint ""
		(layer "F.Cu")
		(at 82.9564 -19.1516 90)
		(property "Reference" "C36"
			(at 0 0 90)
			(layer "F.SilkS")
			(hide yes)
			(effects
				(font
					(size 1.27 1.27)
				)
			)
		)
		(property "Value" "SCD1U25V3KX-GP"
			(at 0 -2.8194 90)
			(unlocked yes)
			(layer "F.Fab")
			(hide yes)
			(effects
				(font
					(size 1.016 1.016)
					(thickness 0.1524)
				)
			)
		)
		(property "Device Type" "C603H36"
			(at 0 -4.3434 90)
			(unlocked yes)
			(layer "F.Fab")
			(hide yes)
			(effects
				(font
					(size 1.016 1.016)
					(thickness 0.1524)
				)
			)
		)
		(duplicate_pad_numbers_are_jumpers no)
		(fp_line
			(start 0.508 0)
			(end -0.508 0)
			(stroke
				(width 0.2032)
				(type default)
			)
			(layer "F.SilkS")
		)
		(fp_rect
			(start -0.5842 1.3335)
			(end 0.5842 -1.3335)
			(stroke
				(width 0)
				(type default)
			)
			(fill no)
			(layer "F.CrtYd")
		)
		(fp_rect
			(start -0.5842 1.3335)
			(end 0.5842 -1.3335)
			(stroke
				(width 0)
				(type default)
			)
			(fill no)
			(layer "F.Fab")
		)
		(pad "1" smd custom
			(at 0 -0.762 90)
			(size 0.2159 0.2159)
			(layers "F.Cu" "F.Mask" "F.Paste")
			(net "P12V")
			(options
				(clearance outline)
				(anchor circle)
			)
			(primitives
				(gr_poly
					(pts
						(arc
							(start -0.3302 -0.4318)
							(mid -0.402042 -0.402042)
							(end -0.4318 -0.3302)
						)
						(arc
							(start -0.4318 0.3302)
							(mid -0.402042 0.402042)
							(end -0.3302 0.4318)
						)
						(arc
							(start 0.3302 0.4318)
							(mid 0.402042 0.402042)
							(end 0.4318 0.3302)
						)
						(arc
							(start 0.4318 -0.3302)
							(mid 0.402042 -0.402042)
							(end 0.3302 -0.4318)
						)
					)
					(width 0)
					(fill yes)
				)
			)
		)
		(pad "2" smd custom
			(at 0 0.762 90)
			(size 0.2159 0.2159)
			(layers "F.Cu" "F.Mask" "F.Paste")
			(net "GND")
			(options
				(clearance outline)
				(anchor circle)
			)
			(primitives
				(gr_poly
					(pts
						(arc
							(start -0.3302 -0.4318)
							(mid -0.402042 -0.402042)
							(end -0.4318 -0.3302)
						)
						(arc
							(start -0.4318 0.3302)
							(mid -0.402042 0.402042)
							(end -0.3302 0.4318)
						)
						(arc
							(start 0.3302 0.4318)
							(mid 0.402042 0.402042)
							(end 0.4318 0.3302)
						)
						(arc
							(start 0.4318 -0.3302)
							(mid 0.402042 -0.402042)
							(end 0.3302 -0.4318)
						)
					)
					(width 0)
					(fill yes)
				)
			)
		)
	)
	(footprint ""
		(layer "F.Cu")
		(at 53.7464 -22.1996 180)
		(property "Reference" "R35"
			(at 0 0 180)
			(layer "F.SilkS")
			(hide yes)
			(effects
				(font
					(size 1.27 1.27)
				)
			)
		)
		(property "Value" "0R2F-1-GP"
			(at 0.064008 -3.993896 180)
			(unlocked yes)
			(layer "F.Fab")
			(hide yes)
			(effects
				(font
					(size 1.016 1.016)
					(thickness 0.1524)
				)
			)
		)
		(property "Device Type" "R402H16"
			(at 0.064008 -5.517896 180)
			(unlocked yes)
			(layer "F.Fab")
			(hide yes)
			(effects
				(font
					(size 1.016 1.016)
					(thickness 0.1524)
				)
			)
		)
		(duplicate_pad_numbers_are_jumpers no)
		(fp_line
			(start 0.508 -0.9398)
			(end -0.508 -0.9398)
			(stroke
				(width 0.1524)
				(type default)
			)
			(layer "F.SilkS")
		)
		(fp_line
			(start -0.508 -0.9398)
			(end -0.508 0.9398)
			(stroke
				(width 0.1524)
				(type default)
			)
			(layer "F.SilkS")
		)
		(fp_rect
			(start -0.508 0.9398)
			(end 0.508 -0.9398)
			(stroke
				(width 0)
				(type default)
			)
			(fill no)
			(layer "F.CrtYd")
		)
		(fp_rect
			(start -0.508 0.9398)
			(end 0.508 -0.9398)
			(stroke
				(width 0)
				(type default)
			)
			(fill no)
			(layer "F.Fab")
		)
		(pad "1" smd custom
			(at 0 -0.4445 180)
			(size 0.1397 0.1397)
			(layers "F.Cu" "F.Mask" "F.Paste")
			(net "SMB_PCIE_SLOT3_ALERT_N")
			(options
				(clearance outline)
				(anchor circle)
			)
			(primitives
				(gr_poly
					(pts
						(arc
							(start -0.1778 -0.2794)
							(mid -0.249642 -0.249642)
							(end -0.2794 -0.1778)
						)
						(arc
							(start -0.2794 0.1778)
							(mid -0.249642 0.249642)
							(end -0.1778 0.2794)
						)
						(arc
							(start 0.1778 0.2794)
							(mid 0.249642 0.249642)
							(end 0.2794 0.1778)
						)
						(arc
							(start 0.2794 -0.1778)
							(mid 0.249642 -0.249642)
							(end 0.1778 -0.2794)
						)
					)
					(width 0)
					(fill yes)
				)
			)
		)
		(pad "2" smd custom
			(at 0 0.4445 180)
			(size 0.1397 0.1397)
			(layers "F.Cu" "F.Mask" "F.Paste")
			(net "SMB_ALERT_S3_B12_N")
			(options
				(clearance outline)
				(anchor circle)
			)
			(primitives
				(gr_poly
					(pts
						(arc
							(start -0.1778 -0.2794)
							(mid -0.249642 -0.249642)
							(end -0.2794 -0.1778)
						)
						(arc
							(start -0.2794 0.1778)
							(mid -0.249642 0.249642)
							(end -0.1778 0.2794)
						)
						(arc
							(start 0.1778 0.2794)
							(mid 0.249642 0.249642)
							(end 0.2794 0.1778)
						)
						(arc
							(start 0.2794 -0.1778)
							(mid 0.249642 -0.249642)
							(end 0.1778 -0.2794)
						)
					)
					(width 0)
					(fill yes)
				)
			)
		)
	)
)
